(kicad_pcb
	(version 20241229)
	(generator "pcbnew")
	(generator_version "9.0")
	(general
		(thickness 1.552)
		(legacy_teardrops no)
	)
	(paper "A4")
	(title_block
		(date "2023-07-25")
		(rev "1.1.4")
		(comment 9 "footprints 350-354 of 379")
	)
	(layers
		(0 "F.Cu" signal)
		(4 "In1.Cu" signal)
		(6 "In2.Cu" signal)
		(8 "In3.Cu" signal)
		(10 "In4.Cu" signal)
		(12 "In5.Cu" signal)
		(14 "In6.Cu" signal)
		(2 "B.Cu" signal)
		(9 "F.Adhes" user "F.Adhesive")
		(11 "B.Adhes" user "B.Adhesive")
		(13 "F.Paste" user)
		(15 "B.Paste" user)
		(5 "F.SilkS" user "F.Silkscreen")
		(7 "B.SilkS" user "B.Silkscreen")
		(1 "F.Mask" user)
		(3 "B.Mask" user)
		(17 "Dwgs.User" user "User.Drawings")
		(19 "Cmts.User" user "User.Comments")
		(21 "Eco1.User" user "User.Eco1")
		(23 "Eco2.User" user "User.Eco2")
		(25 "Edge.Cuts" user)
		(27 "Margin" user)
		(31 "F.CrtYd" user "F.Courtyard")
		(29 "B.CrtYd" user "B.Courtyard")
		(35 "F.Fab" user)
		(33 "B.Fab" user)
	)
	(footprint "antmicro-footprints:C_0402_1005Metric"
		(layer "B.Cu")
		(at 101.8 79.4 180)
		(descr "Capacitor SMD 0402")
		(tags "capacitor SMD 0402")
		(property "Reference" "C72"
			(at -1.03 0.66 0)
			(layer "B.SilkS")
			(effects
				(font
					(size 0.65 0.65)
					(thickness 0.15)
				)
				(justify left bottom mirror)
			)
		)
		(property "Value" "C_100n_0402"
			(at 0 -1.4 0)
			(layer "B.Fab")
			(hide yes)
			(effects
				(font
					(size 0.7 0.7)
					(thickness 0.15)
				)
				(justify left bottom mirror)
			)
		)
		(property "Datasheet" "https://www.murata.com/products/productdetail?partno=GRM155R61H104KE14%23"
			(at 0 0 180)
			(layer "F.Fab")
			(hide yes)
			(effects
				(font
					(size 1.27 1.27)
					(thickness 0.15)
				)
			)
		)
		(property "Description" "SMD Multilayer Ceramic Capacitor, 0.1 µF, 50 V, 0402 [1005 Metric], ± 10%, X5R, GRM Series"
			(at 0 0 180)
			(layer "F.Fab")
			(hide yes)
			(effects
				(font
					(size 1.27 1.27)
					(thickness 0.15)
				)
			)
		)
		(property "Author" "Antmicro"
			(at 203.6 158.8 0)
			(layer "B.Fab")
			(hide yes)
			(effects
				(font
					(size 1 1)
					(thickness 0.15)
				)
				(justify mirror)
			)
		)
		(property "Dielectric" "X5R"
			(at 203.6 158.8 0)
			(layer "B.Fab")
			(hide yes)
			(effects
				(font
					(size 1 1)
					(thickness 0.15)
				)
				(justify mirror)
			)
		)
		(property "License" "Apache-2.0"
			(at 203.6 158.8 0)
			(layer "B.Fab")
			(hide yes)
			(effects
				(font
					(size 1 1)
					(thickness 0.15)
				)
				(justify mirror)
			)
		)
		(property "MPN" "GRM155R61H104KE14D"
			(at 203.6 158.8 0)
			(layer "B.Fab")
			(hide yes)
			(effects
				(font
					(size 1 1)
					(thickness 0.15)
				)
				(justify mirror)
			)
		)
		(property "Manufacturer" "Murata"
			(at 203.6 158.8 0)
			(layer "B.Fab")
			(hide yes)
			(effects
				(font
					(size 1 1)
					(thickness 0.15)
				)
				(justify mirror)
			)
		)
		(property "Val" "100n"
			(at 203.6 158.8 0)
			(layer "B.Fab")
			(hide yes)
			(effects
				(font
					(size 1 1)
					(thickness 0.15)
				)
				(justify mirror)
			)
		)
		(property "Voltage" "50V"
			(at 203.6 158.8 0)
			(layer "B.Fab")
			(hide yes)
			(effects
				(font
					(size 1 1)
					(thickness 0.15)
				)
				(justify mirror)
			)
		)
		(sheetname "/SDI/")
		(sheetfile "sdi.kicad_sch")
		(attr smd)
		(fp_rect
			(start -0.925 0.47)
			(end 0.925 -0.47)
			(stroke
				(width 0.05)
				(type default)
			)
			(fill no)
			(layer "B.CrtYd")
		)
		(fp_line
			(start 0.504 0.25)
			(end 0.504 -0.248)
			(stroke
				(width 0.15)
				(type solid)
			)
			(layer "B.Fab")
		)
		(fp_line
			(start 0.504 -0.248)
			(end -0.494 -0.248)
			(stroke
				(width 0.15)
				(type solid)
			)
			(layer "B.Fab")
		)
		(fp_line
			(start -0.494 0.25)
			(end 0.504 0.25)
			(stroke
				(width 0.15)
				(type solid)
			)
			(layer "B.Fab")
		)
		(fp_line
			(start -0.494 -0.248)
			(end -0.494 0.25)
			(stroke
				(width 0.15)
				(type solid)
			)
			(layer "B.Fab")
		)
		(fp_text user "Author: Antmicro"
			(at -0.939 -3.399 0)
			(layer "B.Fab")
			(effects
				(font
					(size 0.7 0.7)
					(thickness 0.15)
				)
				(justify left bottom mirror)
			)
		)
		(fp_text user "${REFERENCE}"
			(at -0.939 -4.599 0)
			(layer "B.Fab")
			(effects
				(font
					(size 0.7 0.7)
					(thickness 0.15)
				)
				(justify left bottom mirror)
			)
		)
		(fp_text user "License: Apache-2.0"
			(at -0.939 -5.799 0)
			(layer "B.Fab")
			(effects
				(font
					(size 0.7 0.7)
					(thickness 0.15)
				)
				(justify left bottom mirror)
			)
		)
		(pad "1" smd roundrect
			(at -0.48 0 180)
			(size 0.59 0.64)
			(layers "B.Cu" "B.Mask" "B.Paste")
			(roundrect_rratio 0.25)
			(net 1 "GND")
			(pintype "passive")
		)
		(pad "2" smd roundrect
			(at 0.48 0 180)
			(size 0.59 0.64)
			(layers "B.Cu" "B.Mask" "B.Paste")
			(roundrect_rratio 0.25)
			(net 2 "+3V3")
			(pintype "passive")
		)
	)
	(footprint "antmicro-footprints:R_0402_1005Metric"
		(layer "B.Cu")
		(at 94.255 95.25)
		(descr "Resistor SMD 0402")
		(tags "resistor SMD 0402")
		(property "Reference" "R138"
			(at -1.025 0.29 180)
			(layer "B.SilkS")
			(effects
				(font
					(size 0.65 0.65)
					(thickness 0.15)
				)
				(justify left bottom mirror)
			)
		)
		(property "Value" "R_1k_0402"
			(at 0 -1.4 180)
			(layer "B.Fab")
			(hide yes)
			(effects
				(font
					(size 0.7 0.7)
					(thickness 0.15)
				)
				(justify left bottom mirror)
			)
		)
		(property "Datasheet" "https://www.bourns.com/docs/product-datasheets/cr.pdf"
			(at 0 0 0)
			(layer "F.Fab")
			(hide yes)
			(effects
				(font
					(size 1.27 1.27)
					(thickness 0.15)
				)
			)
		)
		(property "Description" "SMD Chip Resistor, 1 kohm, ± 1%, 63 mW, 0402 [1005 Metric], Thick Film, General Purpose"
			(at 0 0 0)
			(layer "F.Fab")
			(hide yes)
			(effects
				(font
					(size 1.27 1.27)
					(thickness 0.15)
				)
			)
		)
		(property "Author" "Antmicro"
			(at 0 0 0)
			(layer "B.Fab")
			(hide yes)
			(effects
				(font
					(size 1 1)
					(thickness 0.15)
				)
				(justify mirror)
			)
		)
		(property "License" "Apache-2.0"
			(at 0 0 0)
			(layer "B.Fab")
			(hide yes)
			(effects
				(font
					(size 1 1)
					(thickness 0.15)
				)
				(justify mirror)
			)
		)
		(property "MPN" "CR0402-FX-1001GLF"
			(at 0 0 0)
			(layer "B.Fab")
			(hide yes)
			(effects
				(font
					(size 1 1)
					(thickness 0.15)
				)
				(justify mirror)
			)
		)
		(property "Manufacturer" "Bourns"
			(at 0 0 0)
			(layer "B.Fab")
			(hide yes)
			(effects
				(font
					(size 1 1)
					(thickness 0.15)
				)
				(justify mirror)
			)
		)
		(property "Tolerance" "1%"
			(at 0 0 0)
			(layer "B.Fab")
			(hide yes)
			(effects
				(font
					(size 1 1)
					(thickness 0.15)
				)
				(justify mirror)
			)
		)
		(property "Val" "1k"
			(at 0 0 0)
			(layer "B.Fab")
			(hide yes)
			(effects
				(font
					(size 1 1)
					(thickness 0.15)
				)
				(justify mirror)
			)
		)
		(sheetname "/SDI/")
		(sheetfile "sdi.kicad_sch")
		(attr smd exclude_from_pos_files exclude_from_bom dnp)
		(fp_rect
			(start -0.925 0.47)
			(end 0.925 -0.47)
			(stroke
				(width 0.05)
				(type default)
			)
			(fill no)
			(layer "B.CrtYd")
		)
		(fp_rect
			(start -0.5 0.25)
			(end 0.5 -0.25)
			(stroke
				(width 0.15)
				(type solid)
			)
			(fill no)
			(layer "B.Fab")
		)
		(fp_text user "Author: Antmicro"
			(at -0.95 -4.169 180)
			(layer "B.Fab")
			(effects
				(font
					(size 0.7 0.7)
					(thickness 0.15)
				)
				(justify left bottom mirror)
			)
		)
		(fp_text user "License: Apache-2.0"
			(at -0.95 -5.169 180)
			(layer "B.Fab")
			(effects
				(font
					(size 0.7 0.7)
					(thickness 0.15)
				)
				(justify left bottom mirror)
			)
		)
		(fp_text user "${REFERENCE}"
			(at -0.95 -3.168 180)
			(layer "B.Fab")
			(effects
				(font
					(size 0.7 0.7)
					(thickness 0.15)
				)
				(justify left bottom mirror)
			)
		)
		(pad "1" smd roundrect
			(at -0.48 0)
			(size 0.59 0.64)
			(layers "B.Cu" "B.Mask" "B.Paste")
			(roundrect_rratio 0.25)
			(net 1 "GND")
			(pintype "passive")
		)
		(pad "2" smd roundrect
			(at 0.48 0)
			(size 0.59 0.64)
			(layers "B.Cu" "B.Mask" "B.Paste")
			(roundrect_rratio 0.25)
			(net 200 "/SDI/20bit{slash}~{10bit}")
			(pintype "passive")
		)
	)
	(footprint "antmicro-footprints:C_0201"
		(layer "B.Cu")
		(at 131.96 96.61 180)
		(descr "Capacitor SMD 0201")
		(tags "capacitor SMD 0201")
		(property "Reference" "C103"
			(at 0.73 -0.53 0)
			(layer "B.SilkS")
			(effects
				(font
					(size 0.65 0.65)
					(thickness 0.15)
				)
				(justify left bottom mirror)
			)
		)
		(property "Value" "C_100n_0201"
			(at 0 -1.4 0)
			(layer "B.Fab")
			(hide yes)
			(effects
				(font
					(size 0.7 0.7)
					(thickness 0.15)
				)
				(justify left bottom mirror)
			)
		)
		(property "Datasheet" "https://www.yageo.com/en/Chart/Download/pdf/CC0201KRX6S5BB104"
			(at 0 0 180)
			(layer "F.Fab")
			(hide yes)
			(effects
				(font
					(size 1.27 1.27)
					(thickness 0.15)
				)
			)
		)
		(property "Description" "SMD Multilayer Ceramic Capacitor, 0.1 µF, 6.3 V, 0201 [0603 Metric], ± 10%, X6S, CC Series"
			(at 0 0 180)
			(layer "F.Fab")
			(hide yes)
			(effects
				(font
					(size 1.27 1.27)
					(thickness 0.15)
				)
			)
		)
		(property "Author" "Antmicro"
			(at 263.92 193.22 0)
			(layer "B.Fab")
			(hide yes)
			(effects
				(font
					(size 1 1)
					(thickness 0.15)
				)
				(justify mirror)
			)
		)
		(property "Dielectric" ""
			(at 263.92 193.22 0)
			(layer "B.Fab")
			(hide yes)
			(effects
				(font
					(size 1 1)
					(thickness 0.15)
				)
				(justify mirror)
			)
		)
		(property "License" "Apache-2.0"
			(at 263.92 193.22 0)
			(layer "B.Fab")
			(hide yes)
			(effects
				(font
					(size 1 1)
					(thickness 0.15)
				)
				(justify mirror)
			)
		)
		(property "MPN" "CC0201KRX6S5BB104"
			(at 263.92 193.22 0)
			(layer "B.Fab")
			(hide yes)
			(effects
				(font
					(size 1 1)
					(thickness 0.15)
				)
				(justify mirror)
			)
		)
		(property "Manufacturer" "YAGEO"
			(at 263.92 193.22 0)
			(layer "B.Fab")
			(hide yes)
			(effects
				(font
					(size 1 1)
					(thickness 0.15)
				)
				(justify mirror)
			)
		)
		(property "Val" "100n"
			(at 263.92 193.22 0)
			(layer "B.Fab")
			(hide yes)
			(effects
				(font
					(size 1 1)
					(thickness 0.15)
				)
				(justify mirror)
			)
		)
		(property "Voltage" ""
			(at 263.92 193.22 0)
			(layer "B.Fab")
			(hide yes)
			(effects
				(font
					(size 1 1)
					(thickness 0.15)
				)
				(justify mirror)
			)
		)
		(property "Public" "False"
			(at 0 0 180)
			(unlocked yes)
			(layer "B.Fab")
			(hide yes)
			(effects
				(font
					(size 1 1)
					(thickness 0.15)
				)
				(justify mirror)
			)
		)
		(sheetname "/FPGA Power/")
		(sheetfile "FPGA_Power.kicad_sch")
		(attr smd)
		(fp_rect
			(start -0.7 0.35)
			(end 0.7 -0.35)
			(stroke
				(width 0.05)
				(type default)
			)
			(fill no)
			(layer "B.CrtYd")
		)
		(fp_rect
			(start 0.3 -0.15)
			(end -0.301 0.149)
			(stroke
				(width 0.15)
				(type solid)
			)
			(fill no)
			(layer "B.Fab")
		)
		(fp_text user "${REFERENCE}"
			(at -0.72 -3.4 0)
			(layer "B.Fab")
			(effects
				(font
					(size 0.7 0.7)
					(thickness 0.15)
				)
				(justify left bottom mirror)
			)
		)
		(fp_text user "Author: Antmicro"
			(at -0.72 -5.4 0)
			(layer "B.Fab")
			(effects
				(font
					(size 0.7 0.7)
					(thickness 0.15)
				)
				(justify left bottom mirror)
			)
		)
		(fp_text user "License: Apache-2.0"
			(at -0.72 -4.4 0)
			(layer "B.Fab")
			(effects
				(font
					(size 0.7 0.7)
					(thickness 0.15)
				)
				(justify left bottom mirror)
			)
		)
		(pad "" smd roundrect
			(at -0.349 0.002 180)
			(size 0.318 0.36)
			(layers "B.Paste")
			(roundrect_rratio 0.25)
		)
		(pad "" smd roundrect
			(at 0.341 0.002 180)
			(size 0.318 0.36)
			(layers "B.Paste")
			(roundrect_rratio 0.25)
		)
		(pad "1" smd roundrect
			(at -0.321 0.002 180)
			(size 0.46 0.4)
			(layers "B.Cu" "B.Mask")
			(roundrect_rratio 0.25)
			(net 1 "GND")
			(pintype "passive")
		)
		(pad "2" smd roundrect
			(at 0.32 0.002 180)
			(size 0.46 0.4)
			(layers "B.Cu" "B.Mask")
			(roundrect_rratio 0.25)
			(net 13 "/FPGA Power/VCC_PLLDPHY")
			(pintype "passive")
		)
	)
	(footprint "antmicro-footprints:R_0402_1005Metric"
		(layer "B.Cu")
		(at 94.255 94.25 180)
		(descr "Resistor SMD 0402")
		(tags "resistor SMD 0402")
		(property "Reference" "R137"
			(at 1.025 -0.29 0)
			(layer "B.SilkS")
			(effects
				(font
					(size 0.65 0.65)
					(thickness 0.15)
				)
				(justify left bottom mirror)
			)
		)
		(property "Value" "R_1k_0402"
			(at 0 -1.4 0)
			(layer "B.Fab")
			(hide yes)
			(effects
				(font
					(size 0.7 0.7)
					(thickness 0.15)
				)
				(justify left bottom mirror)
			)
		)
		(property "Datasheet" "https://www.bourns.com/docs/product-datasheets/cr.pdf"
			(at 0 0 180)
			(layer "F.Fab")
			(hide yes)
			(effects
				(font
					(size 1.27 1.27)
					(thickness 0.15)
				)
			)
		)
		(property "Description" "SMD Chip Resistor, 1 kohm, ± 1%, 63 mW, 0402 [1005 Metric], Thick Film, General Purpose"
			(at 0 0 180)
			(layer "F.Fab")
			(hide yes)
			(effects
				(font
					(size 1.27 1.27)
					(thickness 0.15)
				)
			)
		)
		(property "Author" "Antmicro"
			(at 188.51 188.5 0)
			(layer "B.Fab")
			(hide yes)
			(effects
				(font
					(size 1 1)
					(thickness 0.15)
				)
				(justify mirror)
			)
		)
		(property "License" "Apache-2.0"
			(at 188.51 188.5 0)
			(layer "B.Fab")
			(hide yes)
			(effects
				(font
					(size 1 1)
					(thickness 0.15)
				)
				(justify mirror)
			)
		)
		(property "MPN" "CR0402-FX-1001GLF"
			(at 188.51 188.5 0)
			(layer "B.Fab")
			(hide yes)
			(effects
				(font
					(size 1 1)
					(thickness 0.15)
				)
				(justify mirror)
			)
		)
		(property "Manufacturer" "Bourns"
			(at 188.51 188.5 0)
			(layer "B.Fab")
			(hide yes)
			(effects
				(font
					(size 1 1)
					(thickness 0.15)
				)
				(justify mirror)
			)
		)
		(property "Tolerance" "1%"
			(at 188.51 188.5 0)
			(layer "B.Fab")
			(hide yes)
			(effects
				(font
					(size 1 1)
					(thickness 0.15)
				)
				(justify mirror)
			)
		)
		(property "Val" "1k"
			(at 188.51 188.5 0)
			(layer "B.Fab")
			(hide yes)
			(effects
				(font
					(size 1 1)
					(thickness 0.15)
				)
				(justify mirror)
			)
		)
		(sheetname "/SDI/")
		(sheetfile "sdi.kicad_sch")
		(attr smd)
		(fp_rect
			(start -0.925 0.47)
			(end 0.925 -0.47)
			(stroke
				(width 0.05)
				(type default)
			)
			(fill no)
			(layer "B.CrtYd")
		)
		(fp_rect
			(start -0.5 0.25)
			(end 0.5 -0.25)
			(stroke
				(width 0.15)
				(type solid)
			)
			(fill no)
			(layer "B.Fab")
		)
		(fp_text user "${REFERENCE}"
			(at -0.95 -3.168 0)
			(layer "B.Fab")
			(effects
				(font
					(size 0.7 0.7)
					(thickness 0.15)
				)
				(justify left bottom mirror)
			)
		)
		(fp_text user "Author: Antmicro"
			(at -0.95 -4.169 0)
			(layer "B.Fab")
			(effects
				(font
					(size 0.7 0.7)
					(thickness 0.15)
				)
				(justify left bottom mirror)
			)
		)
		(fp_text user "License: Apache-2.0"
			(at -0.95 -5.169 0)
			(layer "B.Fab")
			(effects
				(font
					(size 0.7 0.7)
					(thickness 0.15)
				)
				(justify left bottom mirror)
			)
		)
		(pad "1" smd roundrect
			(at -0.48 0 180)
			(size 0.59 0.64)
			(layers "B.Cu" "B.Mask" "B.Paste")
			(roundrect_rratio 0.25)
			(net 200 "/SDI/20bit{slash}~{10bit}")
			(pintype "passive")
		)
		(pad "2" smd roundrect
			(at 0.48 0 180)
			(size 0.59 0.64)
			(layers "B.Cu" "B.Mask" "B.Paste")
			(roundrect_rratio 0.25)
			(net 2 "+3V3")
			(pintype "passive")
		)
	)
	(footprint "antmicro-footprints:C_0201"
		(layer "B.Cu")
		(at 129.9 89.9 -135)
		(descr "Capacitor SMD 0201")
		(tags "capacitor SMD 0201")
		(property "Reference" "C65"
			(at -3.129468 15.107857 45)
			(layer "B.SilkS")
			(effects
				(font
					(size 0.65 0.65)
					(thickness 0.15)
				)
				(justify left bottom mirror)
			)
		)
		(property "Value" "C_100n_0201"
			(at 0 -1.399999 45)
			(layer "B.Fab")
			(hide yes)
			(effects
				(font
					(size 0.7 0.7)
					(thickness 0.15)
				)
				(justify left bottom mirror)
			)
		)
		(property "Datasheet" "https://www.yageo.com/en/Chart/Download/pdf/CC0201KRX6S5BB104"
			(at 0 0 225)
			(layer "F.Fab")
			(hide yes)
			(effects
				(font
					(size 1.27 1.27)
					(thickness 0.15)
				)
			)
		)
		(property "Description" "SMD Multilayer Ceramic Capacitor, 0.1 µF, 6.3 V, 0201 [0603 Metric], ± 10%, X6S, CC Series"
			(at 0 0 225)
			(layer "F.Fab")
			(hide yes)
			(effects
				(font
					(size 1.27 1.27)
					(thickness 0.15)
				)
			)
		)
		(property "Author" "Antmicro"
			(at 158.184271 245.322071 0)
			(layer "B.Fab")
			(hide yes)
			(effects
				(font
					(size 1 1)
					(thickness 0.15)
				)
				(justify mirror)
			)
		)
		(property "Dielectric" ""
			(at 158.184271 245.322071 0)
			(layer "B.Fab")
			(hide yes)
			(effects
				(font
					(size 1 1)
					(thickness 0.15)
				)
				(justify mirror)
			)
		)
		(property "License" "Apache-2.0"
			(at 158.184271 245.322071 0)
			(layer "B.Fab")
			(hide yes)
			(effects
				(font
					(size 1 1)
					(thickness 0.15)
				)
				(justify mirror)
			)
		)
		(property "MPN" "CC0201KRX6S5BB104"
			(at 158.184271 245.322071 0)
			(layer "B.Fab")
			(hide yes)
			(effects
				(font
					(size 1 1)
					(thickness 0.15)
				)
				(justify mirror)
			)
		)
		(property "Manufacturer" "YAGEO"
			(at 158.184271 245.322071 0)
			(layer "B.Fab")
			(hide yes)
			(effects
				(font
					(size 1 1)
					(thickness 0.15)
				)
				(justify mirror)
			)
		)
		(property "Val" "100n"
			(at 158.184271 245.322071 0)
			(layer "B.Fab")
			(hide yes)
			(effects
				(font
					(size 1 1)
					(thickness 0.15)
				)
				(justify mirror)
			)
		)
		(property "Voltage" ""
			(at 158.184271 245.322071 0)
			(layer "B.Fab")
			(hide yes)
			(effects
				(font
					(size 1 1)
					(thickness 0.15)
				)
				(justify mirror)
			)
		)
		(property "Public" "False"
			(at 0 0 225)
			(unlocked yes)
			(layer "B.Fab")
			(hide yes)
			(effects
				(font
					(size 1 1)
					(thickness 0.15)
				)
				(justify mirror)
			)
		)
		(sheetname "/SDI/")
		(sheetfile "sdi.kicad_sch")
		(attr smd)
		(fp_poly
			(pts
				(xy -0.7 0.35) (xy 0.7 0.35) (xy 0.7 -0.35) (xy -0.7 -0.35)
			)
			(stroke
				(width 0.05)
				(type default)
			)
			(fill no)
			(layer "B.CrtYd")
		)
		(fp_poly
			(pts
				(xy 0.3 -0.15) (xy -0.301 -0.15) (xy -0.301 0.149) (xy 0.3 0.149)
			)
			(stroke
				(width 0.15)
				(type solid)
			)
			(fill no)
			(layer "B.Fab")
		)
		(fp_text user "License: Apache-2.0"
			(at -0.72 -4.4 45)
			(layer "B.Fab")
			(effects
				(font
					(size 0.7 0.7)
					(thickness 0.15)
				)
				(justify left bottom mirror)
			)
		)
		(fp_text user "Author: Antmicro"
			(at -0.72 -5.400001 45)
			(layer "B.Fab")
			(effects
				(font
					(size 0.7 0.7)
					(thickness 0.15)
				)
				(justify left bottom mirror)
			)
		)
		(fp_text user "${REFERENCE}"
			(at -0.72 -3.4 45)
			(layer "B.Fab")
			(effects
				(font
					(size 0.7 0.7)
					(thickness 0.15)
				)
				(justify left bottom mirror)
			)
		)
		(pad "" smd roundrect
			(at -0.349 0.002 225)
			(size 0.318 0.36)
			(layers "B.Paste")
			(roundrect_rratio 0.25)
		)
		(pad "" smd roundrect
			(at 0.341 0.002 225)
			(size 0.318 0.36)
			(layers "B.Paste")
			(roundrect_rratio 0.25)
		)
		(pad "1" smd roundrect
			(at -0.321 0.002 225)
			(size 0.46 0.4)
			(layers "B.Cu" "B.Mask")
			(roundrect_rratio 0.25)
			(net 1 "GND")
			(pintype "passive")
		)
		(pad "2" smd roundrect
			(at 0.32 0.002 225)
			(size 0.46 0.4)
			(layers "B.Cu" "B.Mask")
			(roundrect_rratio 0.25)
			(net 2 "+3V3")
			(pintype "passive")
		)
	)
)
